(kicad_pcb
	(version 20260206)
	(generator "pcbnew")
	(generator_version "10.0")
	(general
		(thickness 1.6)
		(legacy_teardrops no)
	)
	(paper "A4")
	(title_block
		(title "04192023_DAF0TMB3IC0_F0TG_MB_C_brd_V02_OCP.brd")
		(comment 1 "Grand Teton / footprint 3955 of 8354 (U25), pads 1761-1875 of 6102")
	)
	(layers
		(0 "F.Cu" signal "TOP")
		(4 "In1.Cu" signal "GND")
		(6 "In2.Cu" signal "IN1")
		(8 "In3.Cu" signal "GND1")
		(10 "In4.Cu" signal "IN2")
		(12 "In5.Cu" signal "GND2")
		(14 "In6.Cu" signal "IN3")
		(16 "In7.Cu" signal "GND3")
		(18 "In8.Cu" signal "VCC")
		(20 "In9.Cu" signal "VCC1")
		(22 "In10.Cu" signal "GND4")
		(24 "In11.Cu" signal "IN4")
		(26 "In12.Cu" signal "GND5")
		(28 "In13.Cu" signal "IN5")
		(30 "In14.Cu" signal "GND6")
		(32 "In15.Cu" signal "IN6")
		(34 "In16.Cu" signal "GND7")
		(2 "B.Cu" signal "BOTTOM")
		(9 "F.Adhes" user "F.Adhesive")
		(11 "B.Adhes" user "B.Adhesive")
		(13 "F.Paste" user "Package Geometry/Pastemask Top")
		(15 "B.Paste" user "Package Geometry/Pastemask Bottom")
		(5 "F.SilkS" user "Ref Des/Silkscreen Top")
		(7 "B.SilkS" user "Ref Des/Silkscreen Bottom")
		(1 "F.Mask" user "Board Geometry/Soldermask Top")
		(3 "B.Mask" user "Board Geometry/Soldermask Bottom")
		(17 "Dwgs.User" user "User.Drawings")
		(19 "Cmts.User" user "User.Comments")
		(21 "Eco1.User" user "User.Eco1")
		(23 "Eco2.User" user "User.Eco2")
		(25 "Edge.Cuts" user "Board Geometry/Outline")
		(27 "Margin" user)
		(31 "F.CrtYd" user "Package Geometry/Place Bound Top")
		(29 "B.CrtYd" user "Package Geometry/Place Bound Bottom")
		(35 "F.Fab" user "Ref Des/Assembly Top")
		(33 "B.Fab" user "Ref Des/Assembly Bottom")
	)
	(footprint ""
		(layer "F.Cu")
		(at 359.867962 -258.880102 180)
		(property "Reference" "U25"
			(at -45.78477 -62.086744 0)
			(unlocked yes)
			(layer "F.SilkS")
			(effects
				(font
					(size 0.7874 0.5842)
					(thickness 0.1524)
				)
			)
		)
		(property "Value" ""
			(at 0 0 180)
			(layer "F.Fab")
			(effects
				(font
					(size 1.27 1.27)
				)
			)
		)
		(duplicate_pad_numbers_are_jumpers no)
		(pad "BF4" smd circle
			(at -32.109918 1.97993 180)
			(size 0.450088 0.450088)
			(layers "F.Cu" "F.Mask" "F.Paste")
			(net "TP_M_G_CPU0_SA_TEST39G")
		)
		(pad "BF5" smd circle
			(at -31.170118 1.97993 180)
			(size 0.450088 0.450088)
			(layers "F.Cu" "F.Mask" "F.Paste")
			(net "GND")
		)
		(pad "BF6" smd circle
			(at -30.230064 1.97993 180)
			(size 0.450088 0.450088)
			(layers "F.Cu" "F.Mask" "F.Paste")
			(net "Net_1964")
		)
		(pad "BF7" smd circle
			(at -29.29001 1.97993 180)
			(size 0.450088 0.450088)
			(layers "F.Cu" "F.Mask" "F.Paste")
			(net "TP_M_K_CPU0_SA_TEST39K")
		)
		(pad "BF8" smd circle
			(at -28.349956 1.97993 180)
			(size 0.450088 0.450088)
			(layers "F.Cu" "F.Mask" "F.Paste")
			(net "GND")
		)
		(pad "BF9" smd circle
			(at -27.409902 1.97993 180)
			(size 0.450088 0.450088)
			(layers "F.Cu" "F.Mask" "F.Paste")
			(net "Net_1956")
		)
		(pad "BF10" smd circle
			(at -26.470102 1.97993 180)
			(size 0.450088 0.450088)
			(layers "F.Cu" "F.Mask" "F.Paste")
			(net "GND")
		)
		(pad "BF11" smd circle
			(at -25.530048 1.97993 180)
			(size 0.450088 0.450088)
			(layers "F.Cu" "F.Mask" "F.Paste")
			(net "TP_M_L_CPU0_SA_TEST39L")
		)
		(pad "BF12" smd circle
			(at -24.589994 1.97993 180)
			(size 0.450088 0.450088)
			(layers "F.Cu" "F.Mask" "F.Paste")
			(net "GND")
		)
		(pad "BF13" smd circle
			(at -23.64994 1.97993 180)
			(size 0.450088 0.450088)
			(layers "F.Cu" "F.Mask" "F.Paste")
			(net "Net_1843")
		)
		(pad "BF14" smd circle
			(at -22.709886 1.97993 180)
			(size 0.450088 0.450088)
			(layers "F.Cu" "F.Mask" "F.Paste")
			(net "TP_M_H_CPU0_SA_TEST39H")
		)
		(pad "BF15" smd circle
			(at -21.770086 1.97993 180)
			(size 0.450088 0.450088)
			(layers "F.Cu" "F.Mask" "F.Paste")
			(net "GND")
		)
		(pad "BF16" smd circle
			(at -20.830032 1.97993 180)
			(size 0.450088 0.450088)
			(layers "F.Cu" "F.Mask" "F.Paste")
			(net "Net_1859")
		)
		(pad "BF17" smd circle
			(at -19.889978 1.97993 180)
			(size 0.450088 0.450088)
			(layers "F.Cu" "F.Mask" "F.Paste")
			(net "GND")
		)
		(pad "BF18" smd circle
			(at -18.949924 1.97993 180)
			(size 0.450088 0.450088)
			(layers "F.Cu" "F.Mask" "F.Paste")
			(net "TP_M_J_CPU0_SA_TEST39J")
		)
		(pad "BF19" smd circle
			(at -18.010124 1.97993 180)
			(size 0.450088 0.450088)
			(layers "F.Cu" "F.Mask" "F.Paste")
			(net "GND")
		)
		(pad "BF20" smd circle
			(at -17.07007 1.97993 180)
			(size 0.450088 0.450088)
			(layers "F.Cu" "F.Mask" "F.Paste")
			(net "Net_1851")
		)
		(pad "BF21" smd circle
			(at -16.130016 1.97993 180)
			(size 0.450088 0.450088)
			(layers "F.Cu" "F.Mask" "F.Paste")
			(net "TP_M_I_CPU0_SA_TEST39I")
		)
		(pad "BF22" smd circle
			(at -15.189962 1.97993 180)
			(size 0.450088 0.450088)
			(layers "F.Cu" "F.Mask" "F.Paste")
			(net "GND")
		)
		(pad "BF23" smd circle
			(at -14.249908 1.97993 180)
			(size 0.450088 0.450088)
			(layers "F.Cu" "F.Mask" "F.Paste")
			(net "PVDDCR_SOC_P0")
		)
		(pad "BF24" smd circle
			(at -13.310108 1.97993 180)
			(size 0.450088 0.450088)
			(layers "F.Cu" "F.Mask" "F.Paste")
			(net "GND")
		)
		(pad "BF25" smd circle
			(at -12.370054 1.97993 180)
			(size 0.450088 0.450088)
			(layers "F.Cu" "F.Mask" "F.Paste")
			(net "PVDDCR_SOC_P0")
		)
		(pad "BF26" smd circle
			(at -11.43 1.97993 180)
			(size 0.450088 0.450088)
			(layers "F.Cu" "F.Mask" "F.Paste")
			(net "GND")
		)
		(pad "BF27" smd circle
			(at -10.489946 1.97993 180)
			(size 0.450088 0.450088)
			(layers "F.Cu" "F.Mask" "F.Paste")
			(net "PVDDCR_SOC_P0")
		)
		(pad "BF28" smd circle
			(at -9.549892 1.97993 180)
			(size 0.450088 0.450088)
			(layers "F.Cu" "F.Mask" "F.Paste")
			(net "GND")
		)
		(pad "BF48" smd circle
			(at 9.249918 1.97993 180)
			(size 0.450088 0.450088)
			(layers "F.Cu" "F.Mask" "F.Paste")
			(net "PVDDCR_SOC_P0")
		)
		(pad "BF49" smd circle
			(at 10.189972 1.97993 180)
			(size 0.450088 0.450088)
			(layers "F.Cu" "F.Mask" "F.Paste")
			(net "GND")
		)
		(pad "BF50" smd circle
			(at 11.130026 1.97993 180)
			(size 0.450088 0.450088)
			(layers "F.Cu" "F.Mask" "F.Paste")
			(net "GND")
		)
		(pad "BF51" smd circle
			(at 12.07008 1.97993 180)
			(size 0.450088 0.450088)
			(layers "F.Cu" "F.Mask" "F.Paste")
			(net "PVDDIO_P0")
		)
		(pad "BF52" smd circle
			(at 13.00988 1.97993 180)
			(size 0.450088 0.450088)
			(layers "F.Cu" "F.Mask" "F.Paste")
			(net "GND")
		)
		(pad "BF53" smd circle
			(at 13.949934 1.97993 180)
			(size 0.450088 0.450088)
			(layers "F.Cu" "F.Mask" "F.Paste")
			(net "PVDDIO_P0")
		)
		(pad "BF54" smd circle
			(at 14.889988 1.97993 180)
			(size 0.450088 0.450088)
			(layers "F.Cu" "F.Mask" "F.Paste")
			(net "GND")
		)
		(pad "BF55" smd circle
			(at 15.830042 1.97993 180)
			(size 0.450088 0.450088)
			(layers "F.Cu" "F.Mask" "F.Paste")
			(net "TP_M_C_CPU0_SA_TEST39C")
		)
		(pad "BF56" smd circle
			(at 16.770096 1.97993 180)
			(size 0.450088 0.450088)
			(layers "F.Cu" "F.Mask" "F.Paste")
			(net "Net_1803")
		)
		(pad "BF57" smd circle
			(at 17.709896 1.97993 180)
			(size 0.450088 0.450088)
			(layers "F.Cu" "F.Mask" "F.Paste")
			(net "PVDDIO_P0")
		)
		(pad "BF58" smd circle
			(at 18.64995 1.97993 180)
			(size 0.450088 0.450088)
			(layers "F.Cu" "F.Mask" "F.Paste")
			(net "TP_M_D_CPU0_SA_TEST39D")
		)
		(pad "BF59" smd circle
			(at 19.590004 1.97993 180)
			(size 0.450088 0.450088)
			(layers "F.Cu" "F.Mask" "F.Paste")
			(net "GND")
		)
		(pad "BF60" smd circle
			(at 20.530058 1.97993 180)
			(size 0.450088 0.450088)
			(layers "F.Cu" "F.Mask" "F.Paste")
			(net "Net_1811")
		)
		(pad "BF61" smd circle
			(at 21.470112 1.97993 180)
			(size 0.450088 0.450088)
			(layers "F.Cu" "F.Mask" "F.Paste")
			(net "GND")
		)
		(pad "BF62" smd circle
			(at 22.409912 1.97993 180)
			(size 0.450088 0.450088)
			(layers "F.Cu" "F.Mask" "F.Paste")
			(net "TP_M_B_CPU0_SA_TEST39B")
		)
		(pad "BF63" smd circle
			(at 23.349966 1.97993 180)
			(size 0.450088 0.450088)
			(layers "F.Cu" "F.Mask" "F.Paste")
			(net "Net_1795")
		)
		(pad "BF64" smd circle
			(at 24.29002 1.97993 180)
			(size 0.450088 0.450088)
			(layers "F.Cu" "F.Mask" "F.Paste")
			(net "PVDDIO_P0")
		)
		(pad "BF65" smd circle
			(at 25.230074 1.97993 180)
			(size 0.450088 0.450088)
			(layers "F.Cu" "F.Mask" "F.Paste")
			(net "TP_M_F_CPU0_SA_TEST39F")
		)
		(pad "BF66" smd circle
			(at 26.170128 1.97993 180)
			(size 0.450088 0.450088)
			(layers "F.Cu" "F.Mask" "F.Paste")
			(net "GND")
		)
		(pad "BF67" smd circle
			(at 27.109928 1.97993 180)
			(size 0.450088 0.450088)
			(layers "F.Cu" "F.Mask" "F.Paste")
			(net "Net_1827")
		)
		(pad "BF68" smd circle
			(at 28.049982 1.97993 180)
			(size 0.450088 0.450088)
			(layers "F.Cu" "F.Mask" "F.Paste")
			(net "GND")
		)
		(pad "BF69" smd circle
			(at 28.990036 1.97993 180)
			(size 0.450088 0.450088)
			(layers "F.Cu" "F.Mask" "F.Paste")
			(net "TP_M_E_CPU0_SA_TEST39E")
		)
		(pad "BF70" smd circle
			(at 29.93009 1.97993 180)
			(size 0.450088 0.450088)
			(layers "F.Cu" "F.Mask" "F.Paste")
			(net "Net_1819")
		)
		(pad "BF71" smd circle
			(at 30.86989 1.97993 180)
			(size 0.450088 0.450088)
			(layers "F.Cu" "F.Mask" "F.Paste")
			(net "PVDDIO_P0")
		)
		(pad "BF72" smd circle
			(at 31.809944 1.97993 180)
			(size 0.450088 0.450088)
			(layers "F.Cu" "F.Mask" "F.Paste")
			(net "TP_M_A_CPU0_SA_TEST39A")
		)
		(pad "BF73" smd circle
			(at 32.749998 1.97993 180)
			(size 0.450088 0.450088)
			(layers "F.Cu" "F.Mask" "F.Paste")
			(net "GND")
		)
		(pad "BF74" smd circle
			(at 33.690052 1.97993 180)
			(size 0.450088 0.450088)
			(layers "F.Cu" "F.Mask" "F.Paste")
			(net "Net_1787")
		)
		(pad "BG1" smd circle
			(at -34.459926 2.789936 180)
			(size 0.450088 0.450088)
			(layers "F.Cu" "F.Mask" "F.Paste")
			(net "GND")
		)
		(pad "BG2" smd circle
			(at -33.519872 2.789936 180)
			(size 0.450088 0.450088)
			(layers "F.Cu" "F.Mask" "F.Paste")
			(net "Net_1836")
		)
		(pad "BG3" smd circle
			(at -32.580072 2.789936 180)
			(size 0.450088 0.450088)
			(layers "F.Cu" "F.Mask" "F.Paste")
			(net "M_G_CPU0_SB_CA<0>")
		)
		(pad "BG4" smd circle
			(at -31.640018 2.789936 180)
			(size 0.450088 0.450088)
			(layers "F.Cu" "F.Mask" "F.Paste")
			(net "GND")
		)
		(pad "BG5" smd circle
			(at -30.699964 2.789936 180)
			(size 0.450088 0.450088)
			(layers "F.Cu" "F.Mask" "F.Paste")
			(net "Net_1965")
		)
		(pad "BG6" smd circle
			(at -29.75991 2.789936 180)
			(size 0.450088 0.450088)
			(layers "F.Cu" "F.Mask" "F.Paste")
			(net "GND")
		)
		(pad "BG7" smd circle
			(at -28.82011 2.789936 180)
			(size 0.450088 0.450088)
			(layers "F.Cu" "F.Mask" "F.Paste")
			(net "M_K_CPU0_SB_CA<0>")
		)
		(pad "BG8" smd circle
			(at -27.880056 2.789936 180)
			(size 0.450088 0.450088)
			(layers "F.Cu" "F.Mask" "F.Paste")
			(net "GND")
		)
		(pad "BG9" smd circle
			(at -26.940002 2.789936 180)
			(size 0.450088 0.450088)
			(layers "F.Cu" "F.Mask" "F.Paste")
			(net "Net_1957")
		)
		(pad "BG10" smd circle
			(at -25.999948 2.789936 180)
			(size 0.450088 0.450088)
			(layers "F.Cu" "F.Mask" "F.Paste")
			(net "M_L_CPU0_SB_CA<0>")
		)
		(pad "BG11" smd circle
			(at -25.059894 2.789936 180)
			(size 0.450088 0.450088)
			(layers "F.Cu" "F.Mask" "F.Paste")
			(net "GND")
		)
		(pad "BG12" smd circle
			(at -24.120094 2.789936 180)
			(size 0.450088 0.450088)
			(layers "F.Cu" "F.Mask" "F.Paste")
			(net "Net_1844")
		)
		(pad "BG13" smd circle
			(at -23.18004 2.789936 180)
			(size 0.450088 0.450088)
			(layers "F.Cu" "F.Mask" "F.Paste")
			(net "GND")
		)
		(pad "BG14" smd circle
			(at -22.239986 2.789936 180)
			(size 0.450088 0.450088)
			(layers "F.Cu" "F.Mask" "F.Paste")
			(net "M_H_CPU0_SB_CA<0>")
		)
		(pad "BG15" smd circle
			(at -21.299932 2.789936 180)
			(size 0.450088 0.450088)
			(layers "F.Cu" "F.Mask" "F.Paste")
			(net "GND")
		)
		(pad "BG16" smd circle
			(at -20.359878 2.789936 180)
			(size 0.450088 0.450088)
			(layers "F.Cu" "F.Mask" "F.Paste")
			(net "Net_1860")
		)
		(pad "BG17" smd circle
			(at -19.420078 2.789936 180)
			(size 0.450088 0.450088)
			(layers "F.Cu" "F.Mask" "F.Paste")
			(net "M_J_CPU0_SB_CA<0>")
		)
		(pad "BG18" smd circle
			(at -18.480024 2.789936 180)
			(size 0.450088 0.450088)
			(layers "F.Cu" "F.Mask" "F.Paste")
			(net "GND")
		)
		(pad "BG19" smd circle
			(at -17.53997 2.789936 180)
			(size 0.450088 0.450088)
			(layers "F.Cu" "F.Mask" "F.Paste")
			(net "Net_1852")
		)
		(pad "BG20" smd circle
			(at -16.599916 2.789936 180)
			(size 0.450088 0.450088)
			(layers "F.Cu" "F.Mask" "F.Paste")
			(net "GND")
		)
		(pad "BG21" smd circle
			(at -15.660116 2.789936 180)
			(size 0.450088 0.450088)
			(layers "F.Cu" "F.Mask" "F.Paste")
			(net "M_I_CPU0_SB_CA<0>")
		)
		(pad "BG22" smd circle
			(at -14.720062 2.789936 180)
			(size 0.450088 0.450088)
			(layers "F.Cu" "F.Mask" "F.Paste")
			(net "PVDDCR_SOC_P0")
		)
		(pad "BG23" smd circle
			(at -13.780008 2.789936 180)
			(size 0.450088 0.450088)
			(layers "F.Cu" "F.Mask" "F.Paste")
			(net "GND")
		)
		(pad "BG24" smd circle
			(at -12.839954 2.789936 180)
			(size 0.450088 0.450088)
			(layers "F.Cu" "F.Mask" "F.Paste")
			(net "PVDDCR_SOC_P0")
		)
		(pad "BG25" smd circle
			(at -11.8999 2.789936 180)
			(size 0.450088 0.450088)
			(layers "F.Cu" "F.Mask" "F.Paste")
			(net "GND")
		)
		(pad "BG26" smd circle
			(at -10.9601 2.789936 180)
			(size 0.450088 0.450088)
			(layers "F.Cu" "F.Mask" "F.Paste")
			(net "PVDDCR_SOC_P0")
		)
		(pad "BG27" smd circle
			(at -10.020046 2.789936 180)
			(size 0.450088 0.450088)
			(layers "F.Cu" "F.Mask" "F.Paste")
			(net "GND")
		)
		(pad "BG28" smd circle
			(at -9.079992 2.789936 180)
			(size 0.450088 0.450088)
			(layers "F.Cu" "F.Mask" "F.Paste")
			(net "PVDDCR_SOC_P0")
		)
		(pad "BG48" smd circle
			(at 8.780018 2.789936 180)
			(size 0.450088 0.450088)
			(layers "F.Cu" "F.Mask" "F.Paste")
			(net "PVDDCR_SOC_P0")
		)
		(pad "BG49" smd circle
			(at 9.720072 2.789936 180)
			(size 0.450088 0.450088)
			(layers "F.Cu" "F.Mask" "F.Paste")
			(net "GND")
		)
		(pad "BG50" smd circle
			(at 10.659872 2.789936 180)
			(size 0.450088 0.450088)
			(layers "F.Cu" "F.Mask" "F.Paste")
			(net "PVDDIO_P0")
		)
		(pad "BG51" smd circle
			(at 11.599926 2.789936 180)
			(size 0.450088 0.450088)
			(layers "F.Cu" "F.Mask" "F.Paste")
			(net "GND")
		)
		(pad "BG52" smd circle
			(at 12.53998 2.789936 180)
			(size 0.450088 0.450088)
			(layers "F.Cu" "F.Mask" "F.Paste")
			(net "PVDDIO_P0")
		)
		(pad "BG53" smd circle
			(at 13.480034 2.789936 180)
			(size 0.450088 0.450088)
			(layers "F.Cu" "F.Mask" "F.Paste")
			(net "GND")
		)
		(pad "BG54" smd circle
			(at 14.420088 2.789936 180)
			(size 0.450088 0.450088)
			(layers "F.Cu" "F.Mask" "F.Paste")
			(net "PVDDIO_P0")
		)
		(pad "BG55" smd circle
			(at 15.359888 2.789936 180)
			(size 0.450088 0.450088)
			(layers "F.Cu" "F.Mask" "F.Paste")
			(net "M_C_CPU0_SB_CA<0>")
		)
		(pad "BG56" smd circle
			(at 16.299942 2.789936 180)
			(size 0.450088 0.450088)
			(layers "F.Cu" "F.Mask" "F.Paste")
			(net "GND")
		)
		(pad "BG57" smd circle
			(at 17.239996 2.789936 180)
			(size 0.450088 0.450088)
			(layers "F.Cu" "F.Mask" "F.Paste")
			(net "Net_1804")
		)
		(pad "BG58" smd circle
			(at 18.18005 2.789936 180)
			(size 0.450088 0.450088)
			(layers "F.Cu" "F.Mask" "F.Paste")
			(net "GND")
		)
		(pad "BG59" smd circle
			(at 19.120104 2.789936 180)
			(size 0.450088 0.450088)
			(layers "F.Cu" "F.Mask" "F.Paste")
			(net "M_D_CPU0_SB_CA<0>")
		)
		(pad "BG60" smd circle
			(at 20.059904 2.789936 180)
			(size 0.450088 0.450088)
			(layers "F.Cu" "F.Mask" "F.Paste")
			(net "Net_1812")
		)
		(pad "BG61" smd circle
			(at 20.999958 2.789936 180)
			(size 0.450088 0.450088)
			(layers "F.Cu" "F.Mask" "F.Paste")
			(net "GND")
		)
		(pad "BG62" smd circle
			(at 21.940012 2.789936 180)
			(size 0.450088 0.450088)
			(layers "F.Cu" "F.Mask" "F.Paste")
			(net "M_B_CPU0_SB_CA<0>")
		)
		(pad "BG63" smd circle
			(at 22.880066 2.789936 180)
			(size 0.450088 0.450088)
			(layers "F.Cu" "F.Mask" "F.Paste")
			(net "GND")
		)
		(pad "BG64" smd circle
			(at 23.82012 2.789936 180)
			(size 0.450088 0.450088)
			(layers "F.Cu" "F.Mask" "F.Paste")
			(net "Net_1796")
		)
		(pad "BG65" smd circle
			(at 24.75992 2.789936 180)
			(size 0.450088 0.450088)
			(layers "F.Cu" "F.Mask" "F.Paste")
			(net "GND")
		)
		(pad "BG66" smd circle
			(at 25.699974 2.789936 180)
			(size 0.450088 0.450088)
			(layers "F.Cu" "F.Mask" "F.Paste")
			(net "M_F_CPU0_SB_CA<0>")
		)
		(pad "BG67" smd circle
			(at 26.640028 2.789936 180)
			(size 0.450088 0.450088)
			(layers "F.Cu" "F.Mask" "F.Paste")
			(net "Net_1828")
		)
		(pad "BG68" smd circle
			(at 27.580082 2.789936 180)
			(size 0.450088 0.450088)
			(layers "F.Cu" "F.Mask" "F.Paste")
			(net "GND")
		)
		(pad "BG69" smd circle
			(at 28.519882 2.789936 180)
			(size 0.450088 0.450088)
			(layers "F.Cu" "F.Mask" "F.Paste")
			(net "M_E_CPU0_SB_CA<0>")
		)
		(pad "BG70" smd circle
			(at 29.459936 2.789936 180)
			(size 0.450088 0.450088)
			(layers "F.Cu" "F.Mask" "F.Paste")
			(net "GND")
		)
		(pad "BG71" smd circle
			(at 30.39999 2.789936 180)
			(size 0.450088 0.450088)
			(layers "F.Cu" "F.Mask" "F.Paste")
			(net "Net_1820")
		)
		(pad "BG72" smd circle
			(at 31.340044 2.789936 180)
			(size 0.450088 0.450088)
			(layers "F.Cu" "F.Mask" "F.Paste")
			(net "GND")
		)
		(pad "BG73" smd circle
			(at 32.280098 2.789936 180)
			(size 0.450088 0.450088)
			(layers "F.Cu" "F.Mask" "F.Paste")
			(net "M_A_CPU0_SB_CA<0>")
		)
		(pad "BG74" smd circle
			(at 33.219898 2.789936 180)
			(size 0.450088 0.450088)
			(layers "F.Cu" "F.Mask" "F.Paste")
			(net "Net_1788")
		)
		(pad "BG75" smd circle
			(at 34.159952 2.789936 180)
			(size 0.450088 0.450088)
			(layers "F.Cu" "F.Mask" "F.Paste")
			(net "GND")
		)
		(pad "BH2" smd circle
			(at -33.990026 3.599942 180)
			(size 0.450088 0.450088)
			(layers "F.Cu" "F.Mask" "F.Paste")
			(net "M_G_CPU0_SB_CA<2>")
		)
		(pad "BH3" smd circle
			(at -33.049972 3.599942 180)
			(size 0.450088 0.450088)
			(layers "F.Cu" "F.Mask" "F.Paste")
			(net "GND")
		)
		(pad "BH4" smd circle
			(at -32.109918 3.599942 180)
			(size 0.450088 0.450088)
			(layers "F.Cu" "F.Mask" "F.Paste")
			(net "M_G_CPU0_SB_CA<1>")
		)
		(pad "BH5" smd circle
			(at -31.170118 3.599942 180)
			(size 0.450088 0.450088)
			(layers "F.Cu" "F.Mask" "F.Paste")
			(net "GND")
		)
		(pad "BH6" smd circle
			(at -30.230064 3.599942 180)
			(size 0.450088 0.450088)
			(layers "F.Cu" "F.Mask" "F.Paste")
			(net "M_K_CPU0_SB_CA<2>")
		)
		(pad "BH7" smd circle
			(at -29.29001 3.599942 180)
			(size 0.450088 0.450088)
			(layers "F.Cu" "F.Mask" "F.Paste")
			(net "M_K_CPU0_SB_CA<1>")
		)
		(pad "BH8" smd circle
			(at -28.349956 3.599942 180)
			(size 0.450088 0.450088)
			(layers "F.Cu" "F.Mask" "F.Paste")
			(net "GND")
		)
	)
)
